(kicad_pcb
	(version 20260206)
	(generator "pcbnew")
	(generator_version "10.0")
	(general
		(thickness 1.6)
		(legacy_teardrops no)
	)
	(paper "A4")
	(title_block
		(title "03242023_DA0F0TMBIJ0_F0T_Motherboard_J_brd_V01_OCP.brd")
		(comment 1 "Grand Teton / footprints 5289-5294 of 6105")
	)
	(layers
		(0 "F.Cu" signal "TOP")
		(4 "In1.Cu" signal "GND")
		(6 "In2.Cu" signal "IN1")
		(8 "In3.Cu" signal "GND1")
		(10 "In4.Cu" signal "IN2")
		(12 "In5.Cu" signal "GND2")
		(14 "In6.Cu" signal "IN3")
		(16 "In7.Cu" signal "GND3")
		(18 "In8.Cu" signal "VCC")
		(20 "In9.Cu" signal "VCC1")
		(22 "In10.Cu" signal "GND4")
		(24 "In11.Cu" signal "IN4")
		(26 "In12.Cu" signal "GND5")
		(28 "In13.Cu" signal "IN5")
		(30 "In14.Cu" signal "GND6")
		(32 "In15.Cu" signal "IN6")
		(34 "In16.Cu" signal "GND7")
		(2 "B.Cu" signal "BOTTOM")
		(9 "F.Adhes" user "F.Adhesive")
		(11 "B.Adhes" user "B.Adhesive")
		(13 "F.Paste" user "Package Geometry/Pastemask Top")
		(15 "B.Paste" user "Package Geometry/Pastemask Bottom")
		(5 "F.SilkS" user "Ref Des/Silkscreen Top")
		(7 "B.SilkS" user "Ref Des/Silkscreen Bottom")
		(1 "F.Mask" user "Board Geometry/Soldermask Top")
		(3 "B.Mask" user "Board Geometry/Soldermask Bottom")
		(17 "Dwgs.User" user "User.Drawings")
		(19 "Cmts.User" user "User.Comments")
		(21 "Eco1.User" user "User.Eco1")
		(23 "Eco2.User" user "User.Eco2")
		(25 "Edge.Cuts" user "Board Geometry/Outline")
		(27 "Margin" user)
		(31 "F.CrtYd" user "Package Geometry/Place Bound Top")
		(29 "B.CrtYd" user "Package Geometry/Place Bound Bottom")
		(35 "F.Fab" user "Ref Des/Assembly Top")
		(33 "B.Fab" user "Ref Des/Assembly Bottom")
	)
	(footprint ""
		(layer "B.Cu")
		(at 256.370836 -102.277418 90)
		(property "Reference" "C117"
			(at 0 0 90)
			(layer "B.SilkS")
			(hide yes)
			(effects
				(font
					(size 1.27 1.27)
				)
				(justify mirror)
			)
		)
		(property "Value" ""
			(at 0 0 90)
			(layer "B.Fab")
			(effects
				(font
					(size 1.27 1.27)
				)
				(justify mirror)
			)
		)
		(duplicate_pad_numbers_are_jumpers no)
		(fp_line
			(start 0.7874 -0.4064)
			(end -0.7874 -0.4064)
			(stroke
				(width 0.1524)
				(type default)
			)
			(layer "B.SilkS")
		)
		(fp_line
			(start -0.7874 -0.4064)
			(end -0.7874 0.4064)
			(stroke
				(width 0.1524)
				(type default)
			)
			(layer "B.SilkS")
		)
		(fp_line
			(start 0.7874 0.4064)
			(end 0.7874 -0.4064)
			(stroke
				(width 0.1524)
				(type default)
			)
			(layer "B.SilkS")
		)
		(fp_line
			(start -0.7874 0.4064)
			(end 0.7874 0.4064)
			(stroke
				(width 0.1524)
				(type default)
			)
			(layer "B.SilkS")
		)
		(fp_line
			(start 0.67945 -0.305054)
			(end 0.12065 -0.305054)
			(stroke
				(width 0.1)
				(type default)
			)
			(layer "B.Fab")
		)
		(fp_line
			(start 0.12065 -0.305054)
			(end 0.12065 -0.2794)
			(stroke
				(width 0.1)
				(type default)
			)
			(layer "B.Fab")
		)
		(fp_line
			(start -0.12065 -0.3048)
			(end -0.67945 -0.3048)
			(stroke
				(width 0.1)
				(type default)
			)
			(layer "B.Fab")
		)
		(fp_line
			(start -0.67945 -0.3048)
			(end -0.67945 0.3048)
			(stroke
				(width 0.1)
				(type default)
			)
			(layer "B.Fab")
		)
		(fp_line
			(start 0.12065 -0.2794)
			(end -0.12065 -0.2794)
			(stroke
				(width 0.1)
				(type default)
			)
			(layer "B.Fab")
		)
		(fp_line
			(start -0.12065 -0.2794)
			(end -0.12065 -0.3048)
			(stroke
				(width 0.1)
				(type default)
			)
			(layer "B.Fab")
		)
		(fp_line
			(start 0.12065 0.2794)
			(end 0.12065 0.3048)
			(stroke
				(width 0.1)
				(type default)
			)
			(layer "B.Fab")
		)
		(fp_line
			(start -0.120396 0.2794)
			(end 0.12065 0.2794)
			(stroke
				(width 0.1)
				(type default)
			)
			(layer "B.Fab")
		)
		(fp_line
			(start 0.67945 0.3048)
			(end 0.67945 -0.305054)
			(stroke
				(width 0.1)
				(type default)
			)
			(layer "B.Fab")
		)
		(fp_line
			(start 0.12065 0.3048)
			(end 0.67945 0.3048)
			(stroke
				(width 0.1)
				(type default)
			)
			(layer "B.Fab")
		)
		(fp_line
			(start -0.120396 0.3048)
			(end -0.120396 0.2794)
			(stroke
				(width 0.1)
				(type default)
			)
			(layer "B.Fab")
		)
		(fp_line
			(start -0.67945 0.3048)
			(end -0.120396 0.3048)
			(stroke
				(width 0.1)
				(type default)
			)
			(layer "B.Fab")
		)
		(pad "1" smd circle
			(at 0.40005 0 270)
			(size 0 0)
			(layers "B.Cu" "B.Mask" "B.Paste")
			(net "P3V3_AUX_CLK_GEN_VDDMXCK_CK440")
		)
		(pad "2" smd circle
			(at -0.40005 0 270)
			(size 0 0)
			(layers "B.Cu" "B.Mask" "B.Paste")
			(net "GND")
		)
	)
	(footprint ""
		(layer "B.Cu")
		(at 160.83788 -118.836948)
		(property "Reference" "R986"
			(at 0 0 0)
			(layer "B.SilkS")
			(hide yes)
			(effects
				(font
					(size 1.27 1.27)
				)
				(justify mirror)
			)
		)
		(property "Value" ""
			(at 0 0 0)
			(layer "B.Fab")
			(effects
				(font
					(size 1.27 1.27)
				)
				(justify mirror)
			)
		)
		(duplicate_pad_numbers_are_jumpers no)
		(fp_line
			(start -0.7874 -0.4064)
			(end -0.7874 0.4064)
			(stroke
				(width 0.1524)
				(type default)
			)
			(layer "B.SilkS")
		)
		(fp_line
			(start -0.7874 0.4064)
			(end 0.7874 0.4064)
			(stroke
				(width 0.1524)
				(type default)
			)
			(layer "B.SilkS")
		)
		(fp_line
			(start 0.7874 -0.4064)
			(end -0.7874 -0.4064)
			(stroke
				(width 0.1524)
				(type default)
			)
			(layer "B.SilkS")
		)
		(fp_line
			(start 0.7874 0.4064)
			(end 0.7874 -0.4064)
			(stroke
				(width 0.1524)
				(type default)
			)
			(layer "B.SilkS")
		)
		(fp_line
			(start -0.67945 -0.3048)
			(end -0.67945 0.3048)
			(stroke
				(width 0.1)
				(type default)
			)
			(layer "B.Fab")
		)
		(fp_line
			(start -0.67945 0.3048)
			(end -0.120396 0.3048)
			(stroke
				(width 0.1)
				(type default)
			)
			(layer "B.Fab")
		)
		(fp_line
			(start -0.12065 -0.3048)
			(end -0.67945 -0.3048)
			(stroke
				(width 0.1)
				(type default)
			)
			(layer "B.Fab")
		)
		(fp_line
			(start -0.12065 -0.2794)
			(end -0.12065 -0.3048)
			(stroke
				(width 0.1)
				(type default)
			)
			(layer "B.Fab")
		)
		(fp_line
			(start -0.120396 0.2794)
			(end 0.12065 0.2794)
			(stroke
				(width 0.1)
				(type default)
			)
			(layer "B.Fab")
		)
		(fp_line
			(start -0.120396 0.3048)
			(end -0.120396 0.2794)
			(stroke
				(width 0.1)
				(type default)
			)
			(layer "B.Fab")
		)
		(fp_line
			(start 0.12065 -0.305054)
			(end 0.12065 -0.2794)
			(stroke
				(width 0.1)
				(type default)
			)
			(layer "B.Fab")
		)
		(fp_line
			(start 0.12065 -0.2794)
			(end -0.12065 -0.2794)
			(stroke
				(width 0.1)
				(type default)
			)
			(layer "B.Fab")
		)
		(fp_line
			(start 0.12065 0.2794)
			(end 0.12065 0.3048)
			(stroke
				(width 0.1)
				(type default)
			)
			(layer "B.Fab")
		)
		(fp_line
			(start 0.12065 0.3048)
			(end 0.67945 0.3048)
			(stroke
				(width 0.1)
				(type default)
			)
			(layer "B.Fab")
		)
		(fp_line
			(start 0.67945 -0.305054)
			(end 0.12065 -0.305054)
			(stroke
				(width 0.1)
				(type default)
			)
			(layer "B.Fab")
		)
		(fp_line
			(start 0.67945 0.3048)
			(end 0.67945 -0.305054)
			(stroke
				(width 0.1)
				(type default)
			)
			(layer "B.Fab")
		)
		(pad "1" smd circle
			(at 0.40005 0 180)
			(size 0 0)
			(layers "B.Cu" "B.Mask" "B.Paste")
			(net "FM_PVCCFA_EHV_CPU1_R_EN")
		)
		(pad "2" smd circle
			(at -0.40005 0 180)
			(size 0 0)
			(layers "B.Cu" "B.Mask" "B.Paste")
			(net "FM_PVCCFA_EHV_CPU1_EN")
		)
	)
	(footprint ""
		(layer "B.Cu")
		(at 57.429146 -319.41008 180)
		(property "Reference" "R893"
			(at 0 0 0)
			(layer "B.SilkS")
			(hide yes)
			(effects
				(font
					(size 1.27 1.27)
				)
				(justify mirror)
			)
		)
		(property "Value" ""
			(at 0 0 0)
			(layer "B.Fab")
			(effects
				(font
					(size 1.27 1.27)
				)
				(justify mirror)
			)
		)
		(duplicate_pad_numbers_are_jumpers no)
		(fp_line
			(start 0.7874 0.4064)
			(end 0.7874 -0.4064)
			(stroke
				(width 0.1524)
				(type default)
			)
			(layer "B.SilkS")
		)
		(fp_line
			(start 0.7874 -0.4064)
			(end -0.7874 -0.4064)
			(stroke
				(width 0.1524)
				(type default)
			)
			(layer "B.SilkS")
		)
		(fp_line
			(start -0.7874 0.4064)
			(end 0.7874 0.4064)
			(stroke
				(width 0.1524)
				(type default)
			)
			(layer "B.SilkS")
		)
		(fp_line
			(start -0.7874 -0.4064)
			(end -0.7874 0.4064)
			(stroke
				(width 0.1524)
				(type default)
			)
			(layer "B.SilkS")
		)
		(fp_line
			(start 0.67945 0.3048)
			(end 0.67945 -0.305054)
			(stroke
				(width 0.1)
				(type default)
			)
			(layer "B.Fab")
		)
		(fp_line
			(start 0.67945 -0.305054)
			(end 0.12065 -0.305054)
			(stroke
				(width 0.1)
				(type default)
			)
			(layer "B.Fab")
		)
		(fp_line
			(start 0.12065 0.3048)
			(end 0.67945 0.3048)
			(stroke
				(width 0.1)
				(type default)
			)
			(layer "B.Fab")
		)
		(fp_line
			(start 0.12065 0.2794)
			(end 0.12065 0.3048)
			(stroke
				(width 0.1)
				(type default)
			)
			(layer "B.Fab")
		)
		(fp_line
			(start 0.12065 -0.2794)
			(end -0.12065 -0.2794)
			(stroke
				(width 0.1)
				(type default)
			)
			(layer "B.Fab")
		)
		(fp_line
			(start 0.12065 -0.305054)
			(end 0.12065 -0.2794)
			(stroke
				(width 0.1)
				(type default)
			)
			(layer "B.Fab")
		)
		(fp_line
			(start -0.120396 0.3048)
			(end -0.120396 0.2794)
			(stroke
				(width 0.1)
				(type default)
			)
			(layer "B.Fab")
		)
		(fp_line
			(start -0.120396 0.2794)
			(end 0.12065 0.2794)
			(stroke
				(width 0.1)
				(type default)
			)
			(layer "B.Fab")
		)
		(fp_line
			(start -0.12065 -0.2794)
			(end -0.12065 -0.3048)
			(stroke
				(width 0.1)
				(type default)
			)
			(layer "B.Fab")
		)
		(fp_line
			(start -0.12065 -0.3048)
			(end -0.67945 -0.3048)
			(stroke
				(width 0.1)
				(type default)
			)
			(layer "B.Fab")
		)
		(fp_line
			(start -0.67945 0.3048)
			(end -0.120396 0.3048)
			(stroke
				(width 0.1)
				(type default)
			)
			(layer "B.Fab")
		)
		(fp_line
			(start -0.67945 -0.3048)
			(end -0.67945 0.3048)
			(stroke
				(width 0.1)
				(type default)
			)
			(layer "B.Fab")
		)
		(pad "1" smd circle
			(at 0.40005 0)
			(size 0 0)
			(layers "B.Cu" "B.Mask" "B.Paste")
			(net "PWRGD_CHA_CPU1_DIMM1")
		)
		(pad "2" smd circle
			(at -0.40005 0)
			(size 0 0)
			(layers "B.Cu" "B.Mask" "B.Paste")
			(net "PWRGD_FAIL_CPU1_AB")
		)
	)
	(footprint ""
		(layer "B.Cu")
		(at 83.46948 -331.864208 -90)
		(property "Reference" "PC496_P1_7"
			(at 0 0 90)
			(layer "B.SilkS")
			(hide yes)
			(effects
				(font
					(size 1.27 1.27)
				)
				(justify mirror)
			)
		)
		(property "Value" ""
			(at 0 0 90)
			(layer "B.Fab")
			(effects
				(font
					(size 1.27 1.27)
				)
				(justify mirror)
			)
		)
		(duplicate_pad_numbers_are_jumpers no)
		(fp_line
			(start -0.7874 0.4064)
			(end 0.7874 0.4064)
			(stroke
				(width 0.1524)
				(type default)
			)
			(layer "B.SilkS")
		)
		(fp_line
			(start 0.7874 0.4064)
			(end 0.7874 -0.4064)
			(stroke
				(width 0.1524)
				(type default)
			)
			(layer "B.SilkS")
		)
		(fp_line
			(start -0.7874 -0.4064)
			(end -0.7874 0.4064)
			(stroke
				(width 0.1524)
				(type default)
			)
			(layer "B.SilkS")
		)
		(fp_line
			(start 0.7874 -0.4064)
			(end -0.7874 -0.4064)
			(stroke
				(width 0.1524)
				(type default)
			)
			(layer "B.SilkS")
		)
		(fp_line
			(start -0.67945 0.3048)
			(end -0.120396 0.3048)
			(stroke
				(width 0.1)
				(type default)
			)
			(layer "B.Fab")
		)
		(fp_line
			(start -0.120396 0.3048)
			(end -0.120396 0.2794)
			(stroke
				(width 0.1)
				(type default)
			)
			(layer "B.Fab")
		)
		(fp_line
			(start 0.12065 0.3048)
			(end 0.67945 0.3048)
			(stroke
				(width 0.1)
				(type default)
			)
			(layer "B.Fab")
		)
		(fp_line
			(start 0.67945 0.3048)
			(end 0.67945 -0.305054)
			(stroke
				(width 0.1)
				(type default)
			)
			(layer "B.Fab")
		)
		(fp_line
			(start -0.120396 0.2794)
			(end 0.12065 0.2794)
			(stroke
				(width 0.1)
				(type default)
			)
			(layer "B.Fab")
		)
		(fp_line
			(start 0.12065 0.2794)
			(end 0.12065 0.3048)
			(stroke
				(width 0.1)
				(type default)
			)
			(layer "B.Fab")
		)
		(fp_line
			(start -0.12065 -0.2794)
			(end -0.12065 -0.3048)
			(stroke
				(width 0.1)
				(type default)
			)
			(layer "B.Fab")
		)
		(fp_line
			(start 0.12065 -0.2794)
			(end -0.12065 -0.2794)
			(stroke
				(width 0.1)
				(type default)
			)
			(layer "B.Fab")
		)
		(fp_line
			(start -0.67945 -0.3048)
			(end -0.67945 0.3048)
			(stroke
				(width 0.1)
				(type default)
			)
			(layer "B.Fab")
		)
		(fp_line
			(start -0.12065 -0.3048)
			(end -0.67945 -0.3048)
			(stroke
				(width 0.1)
				(type default)
			)
			(layer "B.Fab")
		)
		(fp_line
			(start 0.12065 -0.305054)
			(end 0.12065 -0.2794)
			(stroke
				(width 0.1)
				(type default)
			)
			(layer "B.Fab")
		)
		(fp_line
			(start 0.67945 -0.305054)
			(end 0.12065 -0.305054)
			(stroke
				(width 0.1)
				(type default)
			)
			(layer "B.Fab")
		)
		(pad "1" smd circle
			(at 0.40005 0 90)
			(size 0 0)
			(layers "B.Cu" "B.Mask" "B.Paste")
			(net "PVCCIN_CPU1")
		)
		(pad "2" smd circle
			(at -0.40005 0 90)
			(size 0 0)
			(layers "B.Cu" "B.Mask" "B.Paste")
			(net "GND")
		)
	)
	(footprint ""
		(layer "B.Cu")
		(at 309.501032 -319.224406)
		(property "Reference" "R27"
			(at 0 0 0)
			(layer "B.SilkS")
			(hide yes)
			(effects
				(font
					(size 1.27 1.27)
				)
				(justify mirror)
			)
		)
		(property "Value" ""
			(at 0 0 0)
			(layer "B.Fab")
			(effects
				(font
					(size 1.27 1.27)
				)
				(justify mirror)
			)
		)
		(duplicate_pad_numbers_are_jumpers no)
		(fp_line
			(start -0.7874 -0.4064)
			(end -0.7874 0.4064)
			(stroke
				(width 0.1524)
				(type default)
			)
			(layer "B.SilkS")
		)
		(fp_line
			(start -0.7874 0.4064)
			(end 0.7874 0.4064)
			(stroke
				(width 0.1524)
				(type default)
			)
			(layer "B.SilkS")
		)
		(fp_line
			(start 0.7874 -0.4064)
			(end -0.7874 -0.4064)
			(stroke
				(width 0.1524)
				(type default)
			)
			(layer "B.SilkS")
		)
		(fp_line
			(start 0.7874 0.4064)
			(end 0.7874 -0.4064)
			(stroke
				(width 0.1524)
				(type default)
			)
			(layer "B.SilkS")
		)
		(fp_line
			(start -0.67945 -0.3048)
			(end -0.67945 0.3048)
			(stroke
				(width 0.1)
				(type default)
			)
			(layer "B.Fab")
		)
		(fp_line
			(start -0.67945 0.3048)
			(end -0.120396 0.3048)
			(stroke
				(width 0.1)
				(type default)
			)
			(layer "B.Fab")
		)
		(fp_line
			(start -0.12065 -0.3048)
			(end -0.67945 -0.3048)
			(stroke
				(width 0.1)
				(type default)
			)
			(layer "B.Fab")
		)
		(fp_line
			(start -0.12065 -0.2794)
			(end -0.12065 -0.3048)
			(stroke
				(width 0.1)
				(type default)
			)
			(layer "B.Fab")
		)
		(fp_line
			(start -0.120396 0.2794)
			(end 0.12065 0.2794)
			(stroke
				(width 0.1)
				(type default)
			)
			(layer "B.Fab")
		)
		(fp_line
			(start -0.120396 0.3048)
			(end -0.120396 0.2794)
			(stroke
				(width 0.1)
				(type default)
			)
			(layer "B.Fab")
		)
		(fp_line
			(start 0.12065 -0.305054)
			(end 0.12065 -0.2794)
			(stroke
				(width 0.1)
				(type default)
			)
			(layer "B.Fab")
		)
		(fp_line
			(start 0.12065 -0.2794)
			(end -0.12065 -0.2794)
			(stroke
				(width 0.1)
				(type default)
			)
			(layer "B.Fab")
		)
		(fp_line
			(start 0.12065 0.2794)
			(end 0.12065 0.3048)
			(stroke
				(width 0.1)
				(type default)
			)
			(layer "B.Fab")
		)
		(fp_line
			(start 0.12065 0.3048)
			(end 0.67945 0.3048)
			(stroke
				(width 0.1)
				(type default)
			)
			(layer "B.Fab")
		)
		(fp_line
			(start 0.67945 -0.305054)
			(end 0.12065 -0.305054)
			(stroke
				(width 0.1)
				(type default)
			)
			(layer "B.Fab")
		)
		(fp_line
			(start 0.67945 0.3048)
			(end 0.67945 -0.305054)
			(stroke
				(width 0.1)
				(type default)
			)
			(layer "B.Fab")
		)
		(pad "1" smd circle
			(at 0.40005 0 180)
			(size 0 0)
			(layers "B.Cu" "B.Mask" "B.Paste")
			(net "PD_CHA_CPU0_DIMM2_SAA")
		)
		(pad "2" smd circle
			(at -0.40005 0 180)
			(size 0 0)
			(layers "B.Cu" "B.Mask" "B.Paste")
			(net "GND")
		)
	)
	(footprint ""
		(layer "B.Cu")
		(at 28.6766 -162.423348 -90)
		(property "Reference" "PR4256"
			(at 0 0 90)
			(layer "B.SilkS")
			(hide yes)
			(effects
				(font
					(size 1.27 1.27)
				)
				(justify mirror)
			)
		)
		(property "Value" ""
			(at 0 0 90)
			(layer "B.Fab")
			(effects
				(font
					(size 1.27 1.27)
				)
				(justify mirror)
			)
		)
		(duplicate_pad_numbers_are_jumpers no)
		(fp_line
			(start -0.7874 0.4064)
			(end 0.7874 0.4064)
			(stroke
				(width 0.1524)
				(type default)
			)
			(layer "B.SilkS")
		)
		(fp_line
			(start 0.7874 0.4064)
			(end 0.7874 -0.4064)
			(stroke
				(width 0.1524)
				(type default)
			)
			(layer "B.SilkS")
		)
		(fp_line
			(start -0.7874 -0.4064)
			(end -0.7874 0.4064)
			(stroke
				(width 0.1524)
				(type default)
			)
			(layer "B.SilkS")
		)
		(fp_line
			(start 0.7874 -0.4064)
			(end -0.7874 -0.4064)
			(stroke
				(width 0.1524)
				(type default)
			)
			(layer "B.SilkS")
		)
		(fp_line
			(start -0.67945 0.3048)
			(end -0.120396 0.3048)
			(stroke
				(width 0.1)
				(type default)
			)
			(layer "B.Fab")
		)
		(fp_line
			(start -0.120396 0.3048)
			(end -0.120396 0.2794)
			(stroke
				(width 0.1)
				(type default)
			)
			(layer "B.Fab")
		)
		(fp_line
			(start 0.12065 0.3048)
			(end 0.67945 0.3048)
			(stroke
				(width 0.1)
				(type default)
			)
			(layer "B.Fab")
		)
		(fp_line
			(start 0.67945 0.3048)
			(end 0.67945 -0.305054)
			(stroke
				(width 0.1)
				(type default)
			)
			(layer "B.Fab")
		)
		(fp_line
			(start -0.120396 0.2794)
			(end 0.12065 0.2794)
			(stroke
				(width 0.1)
				(type default)
			)
			(layer "B.Fab")
		)
		(fp_line
			(start 0.12065 0.2794)
			(end 0.12065 0.3048)
			(stroke
				(width 0.1)
				(type default)
			)
			(layer "B.Fab")
		)
		(fp_line
			(start -0.12065 -0.2794)
			(end -0.12065 -0.3048)
			(stroke
				(width 0.1)
				(type default)
			)
			(layer "B.Fab")
		)
		(fp_line
			(start 0.12065 -0.2794)
			(end -0.12065 -0.2794)
			(stroke
				(width 0.1)
				(type default)
			)
			(layer "B.Fab")
		)
		(fp_line
			(start -0.67945 -0.3048)
			(end -0.67945 0.3048)
			(stroke
				(width 0.1)
				(type default)
			)
			(layer "B.Fab")
		)
		(fp_line
			(start -0.12065 -0.3048)
			(end -0.67945 -0.3048)
			(stroke
				(width 0.1)
				(type default)
			)
			(layer "B.Fab")
		)
		(fp_line
			(start 0.12065 -0.305054)
			(end 0.12065 -0.2794)
			(stroke
				(width 0.1)
				(type default)
			)
			(layer "B.Fab")
		)
		(fp_line
			(start 0.67945 -0.305054)
			(end 0.12065 -0.305054)
			(stroke
				(width 0.1)
				(type default)
			)
			(layer "B.Fab")
		)
		(pad "1" smd circle
			(at 0.40005 0 90)
			(size 0 0)
			(layers "B.Cu" "B.Mask" "B.Paste")
			(net "NC_PVCCD_HV_CPU1_ACSP7")
		)
		(pad "2" smd circle
			(at -0.40005 0 90)
			(size 0 0)
			(layers "B.Cu" "B.Mask" "B.Paste")
			(net "GND")
		)
	)
)
